FILE_TYPE = MULTI_PHYS_TABLE;

PART 'DIODE_2'
CLASS=DISCRETE

{========================================================================================}
:CLS_PN          = JEDEC_TYPE               | ALT_SYMBOLS                | DESCRIPTION                                                       | CPN_STATUS ;
{========================================================================================}
 'CL4000045A'    = 'SOD923'                 | '(SOD923)'                 | '40V 0.2A SCHOTTKY BARRIER DIODE'                                 | ''        
 'CL4000046A'    = 'SMA_403D02'             | '(SMA_403D02)'             | 'SCHOTTKY BARRIER RECTIFIER, 3A, 40V, SMA'                        | ''        
 'CL4000051A'    = 'SMC_CR_169X103'         | '(SMC_CR_169X103)'         | 'DIODE, RECTIFIER, 1A, STANDARD, SMA'                             | ''        
 'CL100654A'     = 'SMC_CR_170X140'         | '(SMC_CR_170X140)'         | 'DIODE,RECTIFIER,1A,.9V,200V'                                     | ''        
 'CL100683A'     = 'X'                      | '(X)'                      | 'DIODE,SCHOTTKY,3A,40V'                                           | ''        
 'CL5001021A'    = 'SMC_CR_170X140'         | '(SMC_CR_170X140)'         | 'SHOTTKY RECTIFIER, 1A, 30V, LOW VF'                              | ''        
 'CL5001025A'    = 'SMC_CR_067X049'         | '(SMC_CR_067X049)'         | 'SCHOTTKY BARRIER DIODE, 0.5A, 30V, LOW VF'                       | ''        
 'CL5001027A'    = 'SMC_CR_106X061'         | '(SMC_CR_106X061)'         | 'DIODE, SINGLE, ZENTER, 43V, 500MW'                               | ''        
 'CL5001032A'    = 'SMC_CR_075X051'         | '(SMC_CR_075X051)'         | 'DIODE, SCHOTTKY BARRIER, 1A, 30V, LOW VF'                        | ''        
 'CL5003003A'    = 'SMC_CR_167X105_V1'      | '(SMC_CR_167X105_V1)'      | 'DIODE,SCHOTTKY,1A,30V'                                           | ''        
 'CL5003004A'    = 'SMC_CR_134X080'         | '(SMC_CR_134X080)'         | 'DIODE,SCHOTTKY,3A,60V'                                           | ''        
 'CL5003011A'    = 'SOD323'                 | '(SOD323)'                 | 'DIO, SCHOTTKY BARRIER SWITCHING, 30V'                            | ''        
 'G122-00017-01' = 'SOD323_FB'              | '(SOD323)'                 | 'DIO, SCHOTTKY BARRIER SWITCHING, 30V'                            | 'NFND'    
 'CL5002043A'    = 'A2_CR094_P383'          | '(A2_CR094_P383)'          | 'DIO, RECTIFIERS, 400V, 1A, -55 TO +175'                          | ''        
 'CL5003016A'    = 'SMC_CR_087X051'         | '(SMC_CR_087X051)'         | 'RECTIFIER, SURFACE MOUNT ESD CAPABILITY, 400 PIV, 1A'            | ''        
 'CL5003029A'    = 'SMC_CR_280X240'         | '(SMC_CR_280X240)'         | 'DIO, POWER RECTIFIER, SCHOTTKY, 100V, 3A, SMC'                   | ''        
 'CL5003026A'    = 'SMA_403D02'             | '(SMA_403D02)'             | 'DIO,RECTIFIER,ULTRAFAST POWER,SURFACE MOUNT,1A,600V'             | ''        
 'CL5003097A'    = 'SMA_403D02'             | '(SMA_403D02)'             | 'DIODE 1A  1000V'                                                 | ''        
 'CL5003187A'    = 'SMC_CR_067X049'         | '(SMC_CR_067X049)'         | 'DIO,HIGH_VOLTAGE_SWITCHING_DIODE, VF _0.95V, 0.1A, 80V,-20~150C' | ''        
 'CL5003215A'    = 'SMC_CR_067X049'         | '(SMC_CR_067X049)'         | 'DIO, HIGH VOLTAGE SWITCHING, VF 0.92V, 0.1A, 80V, SMINI2-F5-B'   | ''        
 'G122-10003-01' = 'SMC_CR_170X143_V1'      | '(SMC_CR_170X143_V1)'      | 'DIO,SURFACE MOUNT ULTRAFAST POWER RECTIFIERS,3A,400V,SMC'        | ''        
 'G122-10039-01' = 'SOD123V3'               | '(SOD123V3)'               | 'DIO, CMHD3595, SMD LOW LEAKAGE, SINGLE, SOD-123'                 | ''        
 'G122-10054-01' = 'SMC_CR_169X103_V2'      | '(SMC_CR_169X103_V2)'      | 'DIO, TVS, SMAJ54A, 54VRWM, 4.6A, 87.1VC, 400W, SMA'              | ''        
 'G122-10064-01' = 'SMC_CR_170X143_V2'      | '(SMC_CR_170X143_V2)'      | 'DIO, SCHOTTKY POWER RECTIFIER, MBRS260T3G, 60V, 2A, SMB'         | ''        
 'G122-10066-01' = 'SMC_CR_169X103_V3'      | '(SMC_CR_169X103_V3)'      | 'DIO, SCHOTTKY POWER RECTIFIER, MBRA160T3G, 60V, 1A, SMA'         | ''        
 'G122-00010-01' = 'SOD323_V2'              | '(SOD323_V2)'              | 'DIO,BAT54H,SCHOTTKY,30V,0.2A,SOD323'                             | ''        
 'G122-10087-01' = 'SMC_CR_169X106'         | '(SMC_CR_169X106)'         | 'DIO,SUPER FAST RECTIFIER,ES1E,300MV,1A,SMA'                      | ''        
 'G122-00005-01' = 'SMC_CR_170X143_V2'      | '(SMC_CR_170X143_V2)'      | 'DIO,MBRS240,SCHOTTKY_PWR_RECT,2A,40V,SMB'                        | ''        
 'G122-10131-01' = 'SOD123_V4'              | '(SOD123_V4)'              | 'DIO,RS1MSWF-7,RECTIFIER,1000V,1A,SOD123F'                        | ''        
 'G122-00011-01' = 'SOD123V3'               | '(SOD123V3)'               | 'DIO,MMSD4148,100V,0.2A,SOD123'                                   | ''        
 'G122-10115-01' = 'SMC_CR_167X105_V4'      | '(SMC_CR_167X105_V4)'      | 'DIO,ES1D,UFAST,200V,1A,DO214AC/SMA'                              | ''        
 'G122-10114-01' = 'SMC_CR_169X103_V2_H094' | '(SMC_CR_169X103_V2_H094)' | 'DIO,US1M,UFAST,1000V,1A,DO214AC/SMA'                             | ''        
 'G122-10125-01' = 'SMC_CR_168X101'         | '(SMC_CR_168X101)'         | 'DIO,ULTRAFAST,STTH1R04A,400V,1A,SMA'                             | ''        
 'G122-10124-01' = 'SOD123V3_H053'          | '(SOD123V3_H053)'          | 'DIO,ZENER,25V,500MW,5%,SOD123'                                   | ''        
 'G122-10142-01' = 'SOD123_V5'              | '(SOD123_V5)'              | 'DIO,SCHOTTKY,S110FA,100V,1A,SOD-123FA'                           | ''        
 'G122-10153-01' = 'SMC_CR_170X102'         | '(SMC_CR_170X102)'         | 'DIO, SCHOTTKY POWER RECTIFIER, MBRA2H100T3G, 100V, 2A, SMA'      | ''        
 'G122-10164-01' = 'TO220_VERTICAL_V6'      | '(TO220_VERTICAL_V6)'      | 'DIO,DHG10I1800PA,SONIC RECOVERY,10A,1800V,TO220'                 | ''        
 'G122-10072-01' = 'SMC_CR_270X230'         | '(SMC_CR_270X230)'         | 'DIO,MURS320T3G,200V,4A,SMC'                                      | ''        
 'A122-00011-HT' = 'SOD123V3_H053'          | '(SOD123V3_H053)'          | 'DIO,FAST SWITCHING,100V,0.2A,SOD123'                             | ''        

END_PART

END.

